(kicad_pcb
	(version 20241229)
	(generator "pcbnew")
	(generator_version "9.0")
	(general
		(thickness 1.63)
		(legacy_teardrops no)
	)
	(paper "A4")
	(title_block
		(title "CM4 Baseboard")
		(date "2026-01-05")
		(rev "1.1.1")
		(company "Antmicro Ltd")
		(comment 1 "www.antmicro.com")
		(comment 9 "footprints 11-15 of 506")
	)
	(layers
		(0 "F.Cu" signal)
		(4 "In1.Cu" power)
		(6 "In2.Cu" power)
		(8 "In3.Cu" signal)
		(10 "In4.Cu" signal)
		(2 "B.Cu" signal)
		(9 "F.Adhes" user "F.Adhesive")
		(11 "B.Adhes" user "B.Adhesive")
		(13 "F.Paste" user)
		(15 "B.Paste" user)
		(5 "F.SilkS" user "F.Silkscreen")
		(7 "B.SilkS" user "B.Silkscreen")
		(1 "F.Mask" user)
		(3 "B.Mask" user)
		(17 "Dwgs.User" user "User.Drawings")
		(19 "Cmts.User" user "User.Comments")
		(21 "Eco1.User" user "User.Eco1")
		(23 "Eco2.User" user "User.Eco2")
		(25 "Edge.Cuts" user)
		(27 "Margin" user)
		(31 "F.CrtYd" user "F.Courtyard")
		(29 "B.CrtYd" user "B.Courtyard")
		(35 "F.Fab" user)
		(33 "B.Fab" user)
	)
	(footprint "antmicro-footprints:C_0402_1005Metric"
		(layer "F.Cu")
		(at 95.897962 121.7165)
		(descr "Capacitor SMD 0402")
		(tags "capacitor SMD 0402")
		(property "Reference" "C901"
			(at 24.885 25.855 0)
			(layer "F.SilkS")
			(effects
				(font
					(size 0.7 0.7)
					(thickness 0.15)
				)
				(justify left bottom)
			)
		)
		(property "Value" "C_100n_0402"
			(at -1.022927 2.155213 0)
			(layer "F.Fab")
			(effects
				(font
					(size 0.7 0.7)
					(thickness 0.15)
				)
				(justify left bottom)
			)
		)
		(property "Datasheet" "https://www.murata.com/products/productdetail?partno=GRM155R61H104KE14%23"
			(at 0 0 0)
			(layer "F.Fab")
			(hide yes)
			(effects
				(font
					(size 1.27 1.27)
					(thickness 0.15)
				)
			)
		)
		(property "Manufacturer" "Murata"
			(at 0 0 0)
			(unlocked yes)
			(layer "F.Fab")
			(hide yes)
			(effects
				(font
					(size 1 1)
					(thickness 0.15)
				)
			)
		)
		(property "MPN" "GRM155R61H104KE14D"
			(at 0 0 0)
			(unlocked yes)
			(layer "F.Fab")
			(hide yes)
			(effects
				(font
					(size 1 1)
					(thickness 0.15)
				)
			)
		)
		(property "Val" "100n"
			(at 0 0 0)
			(unlocked yes)
			(layer "F.Fab")
			(hide yes)
			(effects
				(font
					(size 1 1)
					(thickness 0.15)
				)
			)
		)
		(property "License" "Apache-2.0"
			(at 0 0 0)
			(unlocked yes)
			(layer "F.Fab")
			(hide yes)
			(effects
				(font
					(size 1 1)
					(thickness 0.15)
				)
			)
		)
		(property "Author" "Antmicro"
			(at 0 0 0)
			(unlocked yes)
			(layer "F.Fab")
			(hide yes)
			(effects
				(font
					(size 1 1)
					(thickness 0.15)
				)
			)
		)
		(property "Voltage" "50V"
			(at 0 0 0)
			(unlocked yes)
			(layer "F.Fab")
			(hide yes)
			(effects
				(font
					(size 1 1)
					(thickness 0.15)
				)
			)
		)
		(property "Dielectric" "X5R"
			(at 0 0 0)
			(unlocked yes)
			(layer "F.Fab")
			(hide yes)
			(effects
				(font
					(size 1 1)
					(thickness 0.15)
				)
			)
		)
		(sheetname "/USB/")
		(sheetfile "usb.kicad_sch")
		(attr smd)
		(fp_rect
			(start -0.925 -0.47)
			(end 0.925 0.47)
			(stroke
				(width 0.05)
				(type default)
			)
			(fill no)
			(layer "F.CrtYd")
		)
		(fp_line
			(start -0.494 -0.25)
			(end 0.504 -0.25)
			(stroke
				(width 0.15)
				(type solid)
			)
			(layer "F.Fab")
		)
		(fp_line
			(start -0.494 0.248)
			(end -0.494 -0.25)
			(stroke
				(width 0.15)
				(type solid)
			)
			(layer "F.Fab")
		)
		(fp_line
			(start 0.504 -0.25)
			(end 0.504 0.248)
			(stroke
				(width 0.15)
				(type solid)
			)
			(layer "F.Fab")
		)
		(fp_line
			(start 0.504 0.248)
			(end -0.494 0.248)
			(stroke
				(width 0.15)
				(type solid)
			)
			(layer "F.Fab")
		)
		(fp_text user "${REFERENCE}"
			(at -0.939 4.599 0)
			(layer "F.Fab")
			(effects
				(font
					(size 0.7 0.7)
					(thickness 0.15)
				)
				(justify left bottom)
			)
		)
		(fp_text user "Author: Antmicro"
			(at -0.939 3.399 0)
			(layer "F.Fab")
			(effects
				(font
					(size 0.7 0.7)
					(thickness 0.15)
				)
				(justify left bottom)
			)
		)
		(fp_text user "License: Apache-2.0"
			(at -0.939 5.799 0)
			(layer "F.Fab")
			(effects
				(font
					(size 0.7 0.7)
					(thickness 0.15)
				)
				(justify left bottom)
			)
		)
		(pad "1" smd roundrect
			(at -0.48 0)
			(size 0.59 0.64)
			(layers "F.Cu" "F.Mask" "F.Paste")
			(roundrect_rratio 0.25)
			(net 24 "/Compute module/USBA_VBUS")
			(pintype "passive")
		)
		(pad "2" smd roundrect
			(at 0.48 0)
			(size 0.59 0.64)
			(layers "F.Cu" "F.Mask" "F.Paste")
			(roundrect_rratio 0.25)
			(net 3 "GND")
			(pintype "passive")
		)
	)
	(footprint "antmicro-footprints:C_0402_1005Metric"
		(layer "F.Cu")
		(at 95.897962 122.6565 180)
		(descr "Capacitor SMD 0402")
		(tags "capacitor SMD 0402")
		(property "Reference" "C908"
			(at -27.635 -25.995 0)
			(layer "F.SilkS")
			(effects
				(font
					(size 0.7 0.7)
					(thickness 0.15)
				)
				(justify right bottom)
			)
		)
		(property "Value" "C_10u_0402"
			(at -1.022927 2.155213 0)
			(layer "F.Fab")
			(effects
				(font
					(size 0.7 0.7)
					(thickness 0.15)
				)
				(justify right bottom)
			)
		)
		(property "Datasheet" "https://www.yageo.com/en/Chart/Download/pdf/CC0402MRX5R5BB106"
			(at 0 0 180)
			(layer "F.Fab")
			(hide yes)
			(effects
				(font
					(size 1.27 1.27)
					(thickness 0.15)
				)
			)
		)
		(property "MPN" "CC0402MRX5R5BB106"
			(at 0 0 180)
			(unlocked yes)
			(layer "F.Fab")
			(hide yes)
			(effects
				(font
					(size 1 1)
					(thickness 0.15)
				)
			)
		)
		(property "Manufacturer" "YAGEO"
			(at 0 0 180)
			(unlocked yes)
			(layer "F.Fab")
			(hide yes)
			(effects
				(font
					(size 1 1)
					(thickness 0.15)
				)
			)
		)
		(property "License" "Apache-2.0"
			(at 0 0 180)
			(unlocked yes)
			(layer "F.Fab")
			(hide yes)
			(effects
				(font
					(size 1 1)
					(thickness 0.15)
				)
			)
		)
		(property "Author" "Antmicro"
			(at 0 0 180)
			(unlocked yes)
			(layer "F.Fab")
			(hide yes)
			(effects
				(font
					(size 1 1)
					(thickness 0.15)
				)
			)
		)
		(property "Val" "10u"
			(at 0 0 180)
			(unlocked yes)
			(layer "F.Fab")
			(hide yes)
			(effects
				(font
					(size 1 1)
					(thickness 0.15)
				)
			)
		)
		(property "Voltage" ""
			(at 0 0 180)
			(unlocked yes)
			(layer "F.Fab")
			(hide yes)
			(effects
				(font
					(size 1 1)
					(thickness 0.15)
				)
			)
		)
		(property "Dielectric" ""
			(at 0 0 180)
			(unlocked yes)
			(layer "F.Fab")
			(hide yes)
			(effects
				(font
					(size 1 1)
					(thickness 0.15)
				)
			)
		)
		(sheetname "/USB/")
		(sheetfile "usb.kicad_sch")
		(attr smd)
		(fp_rect
			(start -0.925 -0.47)
			(end 0.925 0.47)
			(stroke
				(width 0.05)
				(type default)
			)
			(fill no)
			(layer "F.CrtYd")
		)
		(fp_line
			(start 0.504 0.248)
			(end -0.494 0.248)
			(stroke
				(width 0.15)
				(type solid)
			)
			(layer "F.Fab")
		)
		(fp_line
			(start 0.504 -0.25)
			(end 0.504 0.248)
			(stroke
				(width 0.15)
				(type solid)
			)
			(layer "F.Fab")
		)
		(fp_line
			(start -0.494 0.248)
			(end -0.494 -0.25)
			(stroke
				(width 0.15)
				(type solid)
			)
			(layer "F.Fab")
		)
		(fp_line
			(start -0.494 -0.25)
			(end 0.504 -0.25)
			(stroke
				(width 0.15)
				(type solid)
			)
			(layer "F.Fab")
		)
		(fp_text user "Author: Antmicro"
			(at -0.939 3.399 180)
			(layer "F.Fab")
			(effects
				(font
					(size 0.7 0.7)
					(thickness 0.15)
				)
				(justify left bottom)
			)
		)
		(fp_text user "License: Apache-2.0"
			(at -0.939 5.799 180)
			(layer "F.Fab")
			(effects
				(font
					(size 0.7 0.7)
					(thickness 0.15)
				)
				(justify left bottom)
			)
		)
		(fp_text user "${REFERENCE}"
			(at -0.939 4.599 180)
			(layer "F.Fab")
			(effects
				(font
					(size 0.7 0.7)
					(thickness 0.15)
				)
				(justify left bottom)
			)
		)
		(pad "1" smd roundrect
			(at -0.48 0 180)
			(size 0.59 0.64)
			(layers "F.Cu" "F.Mask" "F.Paste")
			(roundrect_rratio 0.25)
			(net 3 "GND")
			(pintype "passive")
		)
		(pad "2" smd roundrect
			(at 0.48 0 180)
			(size 0.59 0.64)
			(layers "F.Cu" "F.Mask" "F.Paste")
			(roundrect_rratio 0.25)
			(net 24 "/Compute module/USBA_VBUS")
			(pintype "passive")
		)
	)
	(footprint "antmicro-footprints:TP_SMD_0.75mm"
		(layer "F.Cu")
		(at 53.4 127.45)
		(property "Reference" "TP401"
			(at -0.2 -0.8 90)
			(layer "F.SilkS")
			(effects
				(font
					(size 0.7 0.7)
					(thickness 0.15)
				)
				(justify left bottom)
			)
		)
		(property "Value" "TP_0.75mm_SMD"
			(at 0 1.2 0)
			(layer "F.Fab")
			(effects
				(font
					(size 0.7 0.7)
					(thickness 0.15)
				)
				(justify left bottom)
			)
		)
		(property "MPN" ""
			(at 0 0 0)
			(unlocked yes)
			(layer "F.Fab")
			(hide yes)
			(effects
				(font
					(size 1 1)
					(thickness 0.15)
				)
			)
		)
		(property "Manufacturer" ""
			(at 0 0 0)
			(unlocked yes)
			(layer "F.Fab")
			(hide yes)
			(effects
				(font
					(size 1 1)
					(thickness 0.15)
				)
			)
		)
		(property "Author" "Antmicro"
			(at 0 0 0)
			(unlocked yes)
			(layer "F.Fab")
			(hide yes)
			(effects
				(font
					(size 1 1)
					(thickness 0.15)
				)
			)
		)
		(property "License" "Apache-2.0"
			(at 0 0 0)
			(unlocked yes)
			(layer "F.Fab")
			(hide yes)
			(effects
				(font
					(size 1 1)
					(thickness 0.15)
				)
			)
		)
		(sheetname "/Ethernet/")
		(sheetfile "ethernet.kicad_sch")
		(attr exclude_from_pos_files exclude_from_bom)
		(fp_circle
			(center 0 0)
			(end 0.475 0)
			(stroke
				(width 0.05)
				(type default)
			)
			(fill no)
			(layer "F.CrtYd")
		)
		(fp_text user "License: Apache-2.0"
			(at -0.4 5.101 0)
			(layer "F.Fab")
			(effects
				(font
					(size 0.7 0.7)
					(thickness 0.15)
				)
				(justify left bottom)
			)
		)
		(fp_text user "${REFERENCE}"
			(at -0.4 2.7 0)
			(layer "F.Fab")
			(effects
				(font
					(size 0.7 0.7)
					(thickness 0.15)
				)
				(justify left bottom)
			)
		)
		(fp_text user "Author: Antmicro"
			(at -0.4 3.901 0)
			(layer "F.Fab")
			(effects
				(font
					(size 0.7 0.7)
					(thickness 0.15)
				)
				(justify left bottom)
			)
		)
		(pad "1" smd circle
			(at 0 0)
			(size 0.75 0.75)
			(layers "F.Cu" "F.Mask")
			(net 33 "/Ethernet/VDD")
			(pinfunction "1")
			(pintype "passive")
		)
	)
	(footprint "antmicro-footprints:R_0402_1005Metric"
		(layer "F.Cu")
		(at 76.197962 147.1165 180)
		(descr "Resistor SMD 0402")
		(tags "resistor SMD 0402")
		(property "Reference" "R210"
			(at -1.22 4.95 180)
			(layer "F.SilkS")
			(effects
				(font
					(size 0.7 0.7)
					(thickness 0.15)
				)
				(justify right bottom)
			)
		)
		(property "Value" "R_470R_0402"
			(at -1.011843 1.772047 0)
			(layer "F.Fab")
			(effects
				(font
					(size 0.7 0.7)
					(thickness 0.15)
				)
				(justify right bottom)
			)
		)
		(property "Datasheet" "https://www.bourns.com/docs/product-datasheets/cr.pdf"
			(at 0 0 180)
			(layer "F.Fab")
			(hide yes)
			(effects
				(font
					(size 1.27 1.27)
					(thickness 0.15)
				)
			)
		)
		(property "Manufacturer" "Bourns"
			(at 0 0 180)
			(unlocked yes)
			(layer "F.Fab")
			(hide yes)
			(effects
				(font
					(size 1 1)
					(thickness 0.15)
				)
			)
		)
		(property "MPN" "CR0402-FX-4700GLF"
			(at 0 0 180)
			(unlocked yes)
			(layer "F.Fab")
			(hide yes)
			(effects
				(font
					(size 1 1)
					(thickness 0.15)
				)
			)
		)
		(property "Val" "470R"
			(at 0 0 180)
			(unlocked yes)
			(layer "F.Fab")
			(hide yes)
			(effects
				(font
					(size 1 1)
					(thickness 0.15)
				)
			)
		)
		(property "License" "Apache-2.0"
			(at 0 0 180)
			(unlocked yes)
			(layer "F.Fab")
			(hide yes)
			(effects
				(font
					(size 1 1)
					(thickness 0.15)
				)
			)
		)
		(property "Author" "Antmicro"
			(at 0 0 180)
			(unlocked yes)
			(layer "F.Fab")
			(hide yes)
			(effects
				(font
					(size 1 1)
					(thickness 0.15)
				)
			)
		)
		(property "Tolerance" "1%"
			(at 0 0 180)
			(unlocked yes)
			(layer "F.Fab")
			(hide yes)
			(effects
				(font
					(size 1 1)
					(thickness 0.15)
				)
			)
		)
		(sheetname "/Compute module/")
		(sheetfile "compute-module.kicad_sch")
		(attr smd)
		(fp_rect
			(start -0.925 -0.47)
			(end 0.925 0.47)
			(stroke
				(width 0.05)
				(type default)
			)
			(fill no)
			(layer "F.CrtYd")
		)
		(fp_rect
			(start -0.5 -0.25)
			(end 0.5 0.25)
			(stroke
				(width 0.15)
				(type solid)
			)
			(fill no)
			(layer "F.Fab")
		)
		(fp_text user "License: Apache-2.0"
			(at -0.95 5.169 180)
			(layer "F.Fab")
			(effects
				(font
					(size 0.7 0.7)
					(thickness 0.15)
				)
				(justify left bottom)
			)
		)
		(fp_text user "Author: Antmicro"
			(at -0.95 4.169 180)
			(layer "F.Fab")
			(effects
				(font
					(size 0.7 0.7)
					(thickness 0.15)
				)
				(justify left bottom)
			)
		)
		(fp_text user "${REFERENCE}"
			(at -0.95 3.168 180)
			(layer "F.Fab")
			(effects
				(font
					(size 0.7 0.7)
					(thickness 0.15)
				)
				(justify left bottom)
			)
		)
		(pad "1" smd roundrect
			(at -0.48 0 180)
			(size 0.59 0.64)
			(layers "F.Cu" "F.Mask" "F.Paste")
			(roundrect_rratio 0.25)
			(net 3 "GND")
			(pintype "passive")
		)
		(pad "2" smd roundrect
			(at 0.48 0 180)
			(size 0.59 0.64)
			(layers "F.Cu" "F.Mask" "F.Paste")
			(roundrect_rratio 0.25)
			(net 467 "Net-(D202-C)")
			(pintype "passive")
		)
	)
	(footprint "antmicro-footprints:C_0402_1005Metric"
		(layer "F.Cu")
		(at 86.742962 132.5415 90)
		(descr "Capacitor SMD 0402")
		(tags "capacitor SMD 0402")
		(property "Reference" "C921"
			(at 0.355 -0.545 90)
			(layer "F.SilkS")
			(effects
				(font
					(size 0.7 0.7)
					(thickness 0.15)
				)
				(justify left bottom)
			)
		)
		(property "Value" "C_100n_0402"
			(at -1.022927 2.155213 90)
			(layer "F.Fab")
			(effects
				(font
					(size 0.7 0.7)
					(thickness 0.15)
				)
				(justify left bottom)
			)
		)
		(property "Datasheet" "https://www.murata.com/products/productdetail?partno=GRM155R61H104KE14%23"
			(at 0 0 90)
			(layer "F.Fab")
			(hide yes)
			(effects
				(font
					(size 1.27 1.27)
					(thickness 0.15)
				)
			)
		)
		(property "Manufacturer" "Murata"
			(at 0 0 90)
			(unlocked yes)
			(layer "F.Fab")
			(hide yes)
			(effects
				(font
					(size 1 1)
					(thickness 0.15)
				)
			)
		)
		(property "MPN" "GRM155R61H104KE14D"
			(at 0 0 90)
			(unlocked yes)
			(layer "F.Fab")
			(hide yes)
			(effects
				(font
					(size 1 1)
					(thickness 0.15)
				)
			)
		)
		(property "Val" "100n"
			(at 0 0 90)
			(unlocked yes)
			(layer "F.Fab")
			(hide yes)
			(effects
				(font
					(size 1 1)
					(thickness 0.15)
				)
			)
		)
		(property "License" "Apache-2.0"
			(at 0 0 90)
			(unlocked yes)
			(layer "F.Fab")
			(hide yes)
			(effects
				(font
					(size 1 1)
					(thickness 0.15)
				)
			)
		)
		(property "Author" "Antmicro"
			(at 0 0 90)
			(unlocked yes)
			(layer "F.Fab")
			(hide yes)
			(effects
				(font
					(size 1 1)
					(thickness 0.15)
				)
			)
		)
		(property "Voltage" "50V"
			(at 0 0 90)
			(unlocked yes)
			(layer "F.Fab")
			(hide yes)
			(effects
				(font
					(size 1 1)
					(thickness 0.15)
				)
			)
		)
		(property "Dielectric" "X5R"
			(at 0 0 90)
			(unlocked yes)
			(layer "F.Fab")
			(hide yes)
			(effects
				(font
					(size 1 1)
					(thickness 0.15)
				)
			)
		)
		(sheetname "/USB/")
		(sheetfile "usb.kicad_sch")
		(attr smd)
		(fp_rect
			(start -0.925 -0.47)
			(end 0.925 0.47)
			(stroke
				(width 0.05)
				(type default)
			)
			(fill no)
			(layer "F.CrtYd")
		)
		(fp_line
			(start 0.504 -0.25)
			(end 0.504 0.248)
			(stroke
				(width 0.15)
				(type solid)
			)
			(layer "F.Fab")
		)
		(fp_line
			(start -0.494 -0.25)
			(end 0.504 -0.25)
			(stroke
				(width 0.15)
				(type solid)
			)
			(layer "F.Fab")
		)
		(fp_line
			(start 0.504 0.248)
			(end -0.494 0.248)
			(stroke
				(width 0.15)
				(type solid)
			)
			(layer "F.Fab")
		)
		(fp_line
			(start -0.494 0.248)
			(end -0.494 -0.25)
			(stroke
				(width 0.15)
				(type solid)
			)
			(layer "F.Fab")
		)
		(fp_text user "${REFERENCE}"
			(at -0.939 4.599 90)
			(layer "F.Fab")
			(effects
				(font
					(size 0.7 0.7)
					(thickness 0.15)
				)
				(justify left bottom)
			)
		)
		(fp_text user "License: Apache-2.0"
			(at -0.939 5.799 90)
			(layer "F.Fab")
			(effects
				(font
					(size 0.7 0.7)
					(thickness 0.15)
				)
				(justify left bottom)
			)
		)
		(fp_text user "Author: Antmicro"
			(at -0.939 3.399 90)
			(layer "F.Fab")
			(effects
				(font
					(size 0.7 0.7)
					(thickness 0.15)
				)
				(justify left bottom)
			)
		)
		(pad "1" smd roundrect
			(at -0.48 0 90)
			(size 0.59 0.64)
			(layers "F.Cu" "F.Mask" "F.Paste")
			(roundrect_rratio 0.25)
			(net 30 "/USB/USB_1V2")
			(pintype "passive")
		)
		(pad "2" smd roundrect
			(at 0.48 0 90)
			(size 0.59 0.64)
			(layers "F.Cu" "F.Mask" "F.Paste")
			(roundrect_rratio 0.25)
			(net 3 "GND")
			(pintype "passive")
		)
	)
)
